(kicad_pcb
	(version 20260206)
	(generator "pcbnew")
	(generator_version "10.0")
	(general
		(thickness 1.6)
		(legacy_teardrops no)
	)
	(paper "A4")
	(title_block
		(title "baseboard — 13948-1b.1110WZS1818.brd")
		(comment 1 "Honey Badger (Wiwynn) / footprints 610-617 of 2523")
	)
	(layers
		(0 "F.Cu" signal "TOP")
		(4 "In1.Cu" signal "L2GND")
		(6 "In2.Cu" signal "L3")
		(8 "In3.Cu" signal "L4VCC")
		(10 "In4.Cu" signal "L5VCC")
		(12 "In5.Cu" signal "L6")
		(14 "In6.Cu" signal "L7GND")
		(2 "B.Cu" signal "BOTTOM")
		(9 "F.Adhes" user "F.Adhesive")
		(11 "B.Adhes" user "B.Adhesive")
		(13 "F.Paste" user "Package Geometry/Pastemask Top")
		(15 "B.Paste" user "Package Geometry/Pastemask Bottom")
		(5 "F.SilkS" user "Ref Des/Silkscreen Top")
		(7 "B.SilkS" user "Ref Des/Silkscreen Bottom")
		(1 "F.Mask" user "Board Geometry/Soldermask Top")
		(3 "B.Mask" user "Board Geometry/Soldermask Bottom")
		(17 "Dwgs.User" user "User.Drawings")
		(19 "Cmts.User" user "User.Comments")
		(21 "Eco1.User" user "User.Eco1")
		(23 "Eco2.User" user "User.Eco2")
		(25 "Edge.Cuts" user "Board Geometry/Outline")
		(27 "Margin" user)
		(31 "F.CrtYd" user "Package Geometry/Place Bound Top")
		(29 "B.CrtYd" user "Package Geometry/Place Bound Bottom")
		(35 "F.Fab" user "Ref Des/Assembly Top")
		(33 "B.Fab" user "Ref Des/Assembly Bottom")
	)
	(footprint ""
		(layer "F.Cu")
		(at 323.600064 -9.800082 90)
		(property "Reference" "LED6"
			(at 0 0 90)
			(layer "F.SilkS")
			(hide yes)
			(effects
				(font
					(size 1.27 1.27)
				)
			)
		)
		(property "Value" "LED-R-46-GP"
			(at -2.5527 1.6256 90)
			(unlocked yes)
			(layer "F.Fab")
			(hide yes)
			(effects
				(font
					(size 1.016 1.016)
					(thickness 0.1524)
				)
			)
		)
		(property "Device Type" "LED3215AKH52"
			(at -2.5527 0.1016 90)
			(unlocked yes)
			(layer "F.Fab")
			(hide yes)
			(effects
				(font
					(size 1.016 1.016)
					(thickness 0.1524)
				)
			)
		)
		(duplicate_pad_numbers_are_jumpers no)
		(fp_line
			(start 1.1303 -2.2479)
			(end -1.1303 -2.2479)
			(stroke
				(width 0.1524)
				(type default)
			)
			(layer "F.SilkS")
		)
		(fp_line
			(start -1.1303 -2.2479)
			(end -1.1303 2.2479)
			(stroke
				(width 0.1524)
				(type default)
			)
			(layer "F.SilkS")
		)
		(fp_line
			(start 1.1303 2.2479)
			(end 1.1303 -2.2479)
			(stroke
				(width 0.1524)
				(type default)
			)
			(layer "F.SilkS")
		)
		(fp_line
			(start -1.1303 2.2479)
			(end 1.1303 2.2479)
			(stroke
				(width 0.1524)
				(type default)
			)
			(layer "F.SilkS")
		)
		(fp_line
			(start -1.1303 2.4257)
			(end 1.1303 2.4257)
			(stroke
				(width 0.508)
				(type default)
			)
			(layer "F.SilkS")
		)
		(fp_rect
			(start -1.3843 2.6797)
			(end 1.3843 -2.3241)
			(stroke
				(width 0)
				(type default)
			)
			(fill no)
			(layer "F.CrtYd")
		)
		(fp_rect
			(start -1.3843 2.6797)
			(end 1.3843 -2.3241)
			(stroke
				(width 0)
				(type default)
			)
			(fill no)
			(layer "F.Fab")
		)
		(pad "A" smd rect
			(at 0 -1.36779 90)
			(size 1.7526 1.2446)
			(layers "F.Cu" "F.Mask" "F.Paste")
			(net "LED_SL_SW_ON")
		)
		(pad "K" smd rect
			(at 0 1.36779 90)
			(size 1.7526 1.2446)
			(layers "F.Cu" "F.Mask" "F.Paste")
			(net "DEBUG_LED_SW")
		)
	)
	(footprint ""
		(layer "F.Cu")
		(at 194.1576 -36.6522 -90)
		(property "Reference" "R620"
			(at 0 0 270)
			(layer "F.SilkS")
			(hide yes)
			(effects
				(font
					(size 1.27 1.27)
				)
			)
		)
		(property "Value" "0R2J-2-GP"
			(at 0.064008 -3.993896 270)
			(unlocked yes)
			(layer "F.Fab")
			(hide yes)
			(effects
				(font
					(size 1.016 1.016)
					(thickness 0.1524)
				)
			)
		)
		(property "Device Type" "R402H16"
			(at 0.064008 -5.517896 270)
			(unlocked yes)
			(layer "F.Fab")
			(hide yes)
			(effects
				(font
					(size 1.016 1.016)
					(thickness 0.1524)
				)
			)
		)
		(duplicate_pad_numbers_are_jumpers no)
		(fp_line
			(start -0.508 -0.9398)
			(end -0.508 0.9398)
			(stroke
				(width 0.1524)
				(type default)
			)
			(layer "F.SilkS")
		)
		(fp_line
			(start 0.508 -0.9398)
			(end -0.508 -0.9398)
			(stroke
				(width 0.1524)
				(type default)
			)
			(layer "F.SilkS")
		)
		(fp_rect
			(start -0.508 0.9398)
			(end 0.508 -0.9398)
			(stroke
				(width 0)
				(type default)
			)
			(fill no)
			(layer "F.CrtYd")
		)
		(fp_rect
			(start -0.508 0.9398)
			(end 0.508 -0.9398)
			(stroke
				(width 0)
				(type default)
			)
			(fill no)
			(layer "F.Fab")
		)
		(pad "1" smd custom
			(at 0 -0.4445 270)
			(size 0.1397 0.1397)
			(layers "F.Cu" "F.Mask" "F.Paste")
			(net "GND")
			(options
				(clearance outline)
				(anchor circle)
			)
			(primitives
				(gr_poly
					(pts
						(arc
							(start -0.1778 -0.2794)
							(mid -0.249642 -0.249642)
							(end -0.2794 -0.1778)
						)
						(arc
							(start -0.2794 0.1778)
							(mid -0.249642 0.249642)
							(end -0.1778 0.2794)
						)
						(arc
							(start 0.1778 0.2794)
							(mid 0.249642 0.249642)
							(end 0.2794 0.1778)
						)
						(arc
							(start 0.2794 -0.1778)
							(mid 0.249642 -0.249642)
							(end 0.1778 -0.2794)
						)
					)
					(width 0)
					(fill yes)
				)
			)
		)
		(pad "2" smd custom
			(at 0 0.4445 270)
			(size 0.1397 0.1397)
			(layers "F.Cu" "F.Mask" "F.Paste")
			(net "RMII_BMC_PHY_TXD1")
			(options
				(clearance outline)
				(anchor circle)
			)
			(primitives
				(gr_poly
					(pts
						(arc
							(start -0.1778 -0.2794)
							(mid -0.249642 -0.249642)
							(end -0.2794 -0.1778)
						)
						(arc
							(start -0.2794 0.1778)
							(mid -0.249642 0.249642)
							(end -0.1778 0.2794)
						)
						(arc
							(start 0.1778 0.2794)
							(mid 0.249642 0.249642)
							(end 0.2794 0.1778)
						)
						(arc
							(start 0.2794 -0.1778)
							(mid 0.249642 -0.249642)
							(end 0.1778 -0.2794)
						)
					)
					(width 0)
					(fill yes)
				)
			)
		)
	)
	(footprint ""
		(layer "F.Cu")
		(at 131.318 -90.424 90)
		(property "Reference" "SC1103"
			(at 0 0 90)
			(layer "F.SilkS")
			(hide yes)
			(effects
				(font
					(size 1.27 1.27)
				)
			)
		)
		(property "Value" "SCD01U10V1KX-GP"
			(at -2.8321 -1.7399 90)
			(unlocked yes)
			(layer "F.Fab")
			(hide yes)
			(effects
				(font
					(size 1.016 1.016)
					(thickness 0.1524)
				)
			)
		)
		(property "Device Type" "C0201H13"
			(at -2.8321 -3.2639 90)
			(unlocked yes)
			(layer "F.Fab")
			(hide yes)
			(effects
				(font
					(size 1.016 1.016)
					(thickness 0.1524)
				)
			)
		)
		(duplicate_pad_numbers_are_jumpers no)
		(fp_rect
			(start -0.2794 0.6477)
			(end 0.2794 -0.6477)
			(stroke
				(width 0)
				(type default)
			)
			(fill no)
			(layer "F.CrtYd")
		)
		(fp_rect
			(start -0.2794 0.6477)
			(end 0.2794 -0.6477)
			(stroke
				(width 0)
				(type default)
			)
			(fill no)
			(layer "F.Fab")
		)
		(pad "1" smd custom
			(at 0 -0.2794 90)
			(size 0.0762 0.0762)
			(layers "F.Cu" "F.Mask" "F.Paste")
			(net "3X24_SAS_TX18_N")
			(options
				(clearance outline)
				(anchor circle)
			)
			(primitives
				(gr_poly
					(pts
						(arc
							(start 0.1524 -0.127)
							(mid 0.137521 -0.162921)
							(end 0.1016 -0.1778)
						)
						(arc
							(start -0.1016 -0.1778)
							(mid -0.137521 -0.162921)
							(end -0.1524 -0.127)
						)
						(arc
							(start -0.1524 0.127)
							(mid -0.137521 0.162921)
							(end -0.1016 0.1778)
						)
						(arc
							(start 0.1016 0.1778)
							(mid 0.137521 0.162921)
							(end 0.1524 0.127)
						)
					)
					(width 0)
					(fill yes)
				)
			)
		)
		(pad "2" smd custom
			(at 0 0.2794 90)
			(size 0.0762 0.0762)
			(layers "F.Cu" "F.Mask" "F.Paste")
			(net "SAS_EXP2CONN_TX_N_22")
			(options
				(clearance outline)
				(anchor circle)
			)
			(primitives
				(gr_poly
					(pts
						(arc
							(start 0.1524 -0.127)
							(mid 0.137521 -0.162921)
							(end 0.1016 -0.1778)
						)
						(arc
							(start -0.1016 -0.1778)
							(mid -0.137521 -0.162921)
							(end -0.1524 -0.127)
						)
						(arc
							(start -0.1524 0.127)
							(mid -0.137521 0.162921)
							(end -0.1016 0.1778)
						)
						(arc
							(start 0.1016 0.1778)
							(mid 0.137521 0.162921)
							(end 0.1524 0.127)
						)
					)
					(width 0)
					(fill yes)
				)
			)
		)
	)
	(footprint ""
		(layer "F.Cu")
		(at 336.804 -217.3605)
		(property "Reference" "R183"
			(at 0 0 0)
			(layer "F.SilkS")
			(hide yes)
			(effects
				(font
					(size 1.27 1.27)
				)
			)
		)
		(property "Value" "0R2J-2-GP"
			(at 0.064008 -3.993896 0)
			(unlocked yes)
			(layer "F.Fab")
			(hide yes)
			(effects
				(font
					(size 1.016 1.016)
					(thickness 0.1524)
				)
			)
		)
		(property "Device Type" "R402H16"
			(at 0.064008 -5.517896 0)
			(unlocked yes)
			(layer "F.Fab")
			(hide yes)
			(effects
				(font
					(size 1.016 1.016)
					(thickness 0.1524)
				)
			)
		)
		(duplicate_pad_numbers_are_jumpers no)
		(fp_line
			(start -0.508 -0.9398)
			(end -0.508 0.9398)
			(stroke
				(width 0.1524)
				(type default)
			)
			(layer "F.SilkS")
		)
		(fp_line
			(start 0.508 -0.9398)
			(end -0.508 -0.9398)
			(stroke
				(width 0.1524)
				(type default)
			)
			(layer "F.SilkS")
		)
		(fp_rect
			(start -0.508 0.9398)
			(end 0.508 -0.9398)
			(stroke
				(width 0)
				(type default)
			)
			(fill no)
			(layer "F.CrtYd")
		)
		(fp_rect
			(start -0.508 0.9398)
			(end 0.508 -0.9398)
			(stroke
				(width 0)
				(type default)
			)
			(fill no)
			(layer "F.Fab")
		)
		(pad "1" smd custom
			(at 0 -0.4445)
			(size 0.1397 0.1397)
			(layers "F.Cu" "F.Mask" "F.Paste")
			(net "VOL_SEN_SCL")
			(options
				(clearance outline)
				(anchor circle)
			)
			(primitives
				(gr_poly
					(pts
						(arc
							(start -0.1778 -0.2794)
							(mid -0.249642 -0.249642)
							(end -0.2794 -0.1778)
						)
						(arc
							(start -0.2794 0.1778)
							(mid -0.249642 0.249642)
							(end -0.1778 0.2794)
						)
						(arc
							(start 0.1778 0.2794)
							(mid 0.249642 0.249642)
							(end 0.2794 0.1778)
						)
						(arc
							(start 0.2794 -0.1778)
							(mid 0.249642 -0.249642)
							(end 0.1778 -0.2794)
						)
					)
					(width 0)
					(fill yes)
				)
			)
		)
		(pad "2" smd custom
			(at 0 0.4445)
			(size 0.1397 0.1397)
			(layers "F.Cu" "F.Mask" "F.Paste")
			(net "BMC_I2C_A_SCL")
			(options
				(clearance outline)
				(anchor circle)
			)
			(primitives
				(gr_poly
					(pts
						(arc
							(start -0.1778 -0.2794)
							(mid -0.249642 -0.249642)
							(end -0.2794 -0.1778)
						)
						(arc
							(start -0.2794 0.1778)
							(mid -0.249642 0.249642)
							(end -0.1778 0.2794)
						)
						(arc
							(start 0.1778 0.2794)
							(mid 0.249642 0.249642)
							(end 0.2794 0.1778)
						)
						(arc
							(start 0.2794 -0.1778)
							(mid 0.249642 -0.249642)
							(end 0.1778 -0.2794)
						)
					)
					(width 0)
					(fill yes)
				)
			)
		)
	)
	(footprint ""
		(layer "F.Cu")
		(at 289.433 -156.972 -90)
		(property "Reference" "R421"
			(at 0 0 270)
			(layer "F.SilkS")
			(hide yes)
			(effects
				(font
					(size 1.27 1.27)
				)
			)
		)
		(property "Value" "2K2R2J-2-GP"
			(at 0.064008 -3.993896 270)
			(unlocked yes)
			(layer "F.Fab")
			(hide yes)
			(effects
				(font
					(size 1.016 1.016)
					(thickness 0.1524)
				)
			)
		)
		(property "Device Type" "R402H16"
			(at 0.064008 -5.517896 270)
			(unlocked yes)
			(layer "F.Fab")
			(hide yes)
			(effects
				(font
					(size 1.016 1.016)
					(thickness 0.1524)
				)
			)
		)
		(duplicate_pad_numbers_are_jumpers no)
		(fp_line
			(start -0.508 -0.9398)
			(end -0.508 0.9398)
			(stroke
				(width 0.1524)
				(type default)
			)
			(layer "F.SilkS")
		)
		(fp_line
			(start 0.508 -0.9398)
			(end -0.508 -0.9398)
			(stroke
				(width 0.1524)
				(type default)
			)
			(layer "F.SilkS")
		)
		(fp_rect
			(start -0.508 0.9398)
			(end 0.508 -0.9398)
			(stroke
				(width 0)
				(type default)
			)
			(fill no)
			(layer "F.CrtYd")
		)
		(fp_rect
			(start -0.508 0.9398)
			(end 0.508 -0.9398)
			(stroke
				(width 0)
				(type default)
			)
			(fill no)
			(layer "F.Fab")
		)
		(pad "1" smd custom
			(at 0 -0.4445 270)
			(size 0.1397 0.1397)
			(layers "F.Cu" "F.Mask" "F.Paste")
			(net "P3V3_STBY")
			(options
				(clearance outline)
				(anchor circle)
			)
			(primitives
				(gr_poly
					(pts
						(arc
							(start -0.1778 -0.2794)
							(mid -0.249642 -0.249642)
							(end -0.2794 -0.1778)
						)
						(arc
							(start -0.2794 0.1778)
							(mid -0.249642 0.249642)
							(end -0.1778 0.2794)
						)
						(arc
							(start 0.1778 0.2794)
							(mid 0.249642 0.249642)
							(end 0.2794 0.1778)
						)
						(arc
							(start 0.2794 -0.1778)
							(mid 0.249642 -0.249642)
							(end 0.1778 -0.2794)
						)
					)
					(width 0)
					(fill yes)
				)
			)
		)
		(pad "2" smd custom
			(at 0 0.4445 270)
			(size 0.1397 0.1397)
			(layers "F.Cu" "F.Mask" "F.Paste")
			(net "CPU_BMC_UART_TX")
			(options
				(clearance outline)
				(anchor circle)
			)
			(primitives
				(gr_poly
					(pts
						(arc
							(start -0.1778 -0.2794)
							(mid -0.249642 -0.249642)
							(end -0.2794 -0.1778)
						)
						(arc
							(start -0.2794 0.1778)
							(mid -0.249642 0.249642)
							(end -0.1778 0.2794)
						)
						(arc
							(start 0.1778 0.2794)
							(mid 0.249642 0.249642)
							(end 0.2794 0.1778)
						)
						(arc
							(start 0.2794 -0.1778)
							(mid 0.249642 -0.249642)
							(end 0.1778 -0.2794)
						)
					)
					(width 0)
					(fill yes)
				)
			)
		)
	)
	(footprint ""
		(layer "F.Cu")
		(at 85.452966 -84.074 180)
		(property "Reference" "SC1155"
			(at 0 0 180)
			(layer "F.SilkS")
			(hide yes)
			(effects
				(font
					(size 1.27 1.27)
				)
			)
		)
		(property "Value" "SC10U6D3V5KX-4GP"
			(at -0.0762 -6.1214 180)
			(unlocked yes)
			(layer "F.Fab")
			(hide yes)
			(effects
				(font
					(size 1.016 1.016)
					(thickness 0.1524)
				)
			)
		)
		(property "Device Type" "C805H58"
			(at -0.0762 -8.1534 180)
			(unlocked yes)
			(layer "F.Fab")
			(hide yes)
			(effects
				(font
					(size 1.016 1.016)
					(thickness 0.1524)
				)
			)
		)
		(duplicate_pad_numbers_are_jumpers no)
		(fp_line
			(start 0.635 0)
			(end -0.635 0)
			(stroke
				(width 0.508)
				(type default)
			)
			(layer "F.SilkS")
		)
		(fp_rect
			(start -0.9652 1.778)
			(end 0.9652 -1.778)
			(stroke
				(width 0)
				(type default)
			)
			(fill no)
			(layer "F.CrtYd")
		)
		(fp_poly
			(pts
				(xy -0.9652 -1.778) (xy 0.9652 -1.778) (xy 0.9652 1.778) (xy -0.9652 1.778)
			)
			(stroke
				(width 0)
				(type default)
			)
			(fill no)
			(layer "F.Fab")
		)
		(pad "1" smd rect
			(at 0 -0.9652 180)
			(size 1.397 1.143)
			(layers "F.Cu" "F.Mask" "F.Paste")
			(net "PLLDDR_VDDA18")
		)
		(pad "2" smd rect
			(at 0 0.9652 180)
			(size 1.397 1.143)
			(layers "F.Cu" "F.Mask" "F.Paste")
			(net "GND")
		)
	)
	(footprint ""
		(layer "F.Cu")
		(at 174.107348 -121.783856 90)
		(property "Reference" "PC169"
			(at 0 0 90)
			(layer "F.SilkS")
			(hide yes)
			(effects
				(font
					(size 1.27 1.27)
				)
			)
		)
		(property "Value" "SC22U25V5MX-GP"
			(at -0.0762 -6.1214 90)
			(unlocked yes)
			(layer "F.Fab")
			(hide yes)
			(effects
				(font
					(size 1.016 1.016)
					(thickness 0.1524)
				)
			)
		)
		(property "Device Type" "C805H58"
			(at -0.0762 -8.1534 90)
			(unlocked yes)
			(layer "F.Fab")
			(hide yes)
			(effects
				(font
					(size 1.016 1.016)
					(thickness 0.1524)
				)
			)
		)
		(duplicate_pad_numbers_are_jumpers no)
		(fp_line
			(start 0.635 0)
			(end -0.635 0)
			(stroke
				(width 0.508)
				(type default)
			)
			(layer "F.SilkS")
		)
		(fp_rect
			(start -0.9652 1.778)
			(end 0.9652 -1.778)
			(stroke
				(width 0)
				(type default)
			)
			(fill no)
			(layer "F.CrtYd")
		)
		(fp_poly
			(pts
				(xy -0.9652 -1.778) (xy 0.9652 -1.778) (xy 0.9652 1.778) (xy -0.9652 1.778)
			)
			(stroke
				(width 0)
				(type default)
			)
			(fill no)
			(layer "F.Fab")
		)
		(pad "1" smd rect
			(at 0 -0.9652 90)
			(size 1.397 1.143)
			(layers "F.Cu" "F.Mask" "F.Paste")
			(net "P0V9_E_VIN")
		)
		(pad "2" smd rect
			(at 0 0.9652 90)
			(size 1.397 1.143)
			(layers "F.Cu" "F.Mask" "F.Paste")
			(net "GND")
		)
	)
	(footprint ""
		(layer "F.Cu")
		(at 284.0482 -191.77)
		(property "Reference" "C183"
			(at 0 0 0)
			(layer "F.SilkS")
			(hide yes)
			(effects
				(font
					(size 1.27 1.27)
				)
			)
		)
		(property "Value" "SCD1U16V2KX-3GP"
			(at 1.1811 -2.7051 0)
			(unlocked yes)
			(layer "F.Fab")
			(hide yes)
			(effects
				(font
					(size 1.016 1.016)
					(thickness 0.1524)
				)
			)
		)
		(property "Device Type" "C402H22"
			(at 1.1811 -4.2291 0)
			(unlocked yes)
			(layer "F.Fab")
			(hide yes)
			(effects
				(font
					(size 1.016 1.016)
					(thickness 0.1524)
				)
			)
		)
		(duplicate_pad_numbers_are_jumpers no)
		(fp_rect
			(start -0.4318 0.9525)
			(end 0.4318 -0.9525)
			(stroke
				(width 0)
				(type default)
			)
			(fill no)
			(layer "F.CrtYd")
		)
		(fp_rect
			(start -0.4318 0.9525)
			(end 0.4318 -0.9525)
			(stroke
				(width 0)
				(type default)
			)
			(fill no)
			(layer "F.Fab")
		)
		(pad "1" smd custom
			(at 0 -0.4445)
			(size 0.1524 0.1524)
			(layers "F.Cu" "F.Mask" "F.Paste")
			(net "P1V53_STBY")
			(options
				(clearance outline)
				(anchor circle)
			)
			(primitives
				(gr_poly
					(pts
						(arc
							(start 0.3048 -0.2032)
							(mid 0.275042 -0.275042)
							(end 0.2032 -0.3048)
						)
						(arc
							(start -0.2032 -0.3048)
							(mid -0.275042 -0.275042)
							(end -0.3048 -0.2032)
						)
						(arc
							(start -0.3048 0.2032)
							(mid -0.275042 0.275042)
							(end -0.2032 0.3048)
						)
						(arc
							(start 0.2032 0.3048)
							(mid 0.275042 0.275042)
							(end 0.3048 0.2032)
						)
					)
					(width 0)
					(fill yes)
				)
			)
		)
		(pad "2" smd custom
			(at 0 0.4445)
			(size 0.1524 0.1524)
			(layers "F.Cu" "F.Mask" "F.Paste")
			(net "GND")
			(options
				(clearance outline)
				(anchor circle)
			)
			(primitives
				(gr_poly
					(pts
						(arc
							(start 0.3048 -0.2032)
							(mid 0.275042 -0.275042)
							(end 0.2032 -0.3048)
						)
						(arc
							(start -0.2032 -0.3048)
							(mid -0.275042 -0.275042)
							(end -0.3048 -0.2032)
						)
						(arc
							(start -0.3048 0.2032)
							(mid -0.275042 0.275042)
							(end -0.2032 0.3048)
						)
						(arc
							(start 0.2032 0.3048)
							(mid 0.275042 0.275042)
							(end 0.3048 0.2032)
						)
					)
					(width 0)
					(fill yes)
				)
			)
		)
	)
)
